# T6G (Grand Teton) — schematic netlist excerpt (pin names and nets, part order shuffled) for the footprints in the layout excerpt that follows; sources: Cadence DE-HDL packaged netlist, KiCad conversion of 04192023_DAF0TMB3IC0_F0TG_MB_C_brd_V02_OCP.brd

C1786  Q_CAP  1000PF 50V 10% X7R  pkg 0603  page 267 : A = P12V_HSC_TEMP_D+ ; B = P12V_HSC_TEMP_D-
R364  Q_RES  0 5% CHIP  pkg 0402LF  page 151 : A = P3V_BAT_R ; B = SCM_VDD_RTC
C1558  Q_CAP_DIFFBUS  DIFF BUS_0.22UF 6.3V 20% X6S  pkg C0201  page 65 : \1\ = P5E_CPU0_G3_TX_C_DN<10> ; \2\ = P5E_CPU0_G3_TX_DN<10>

(kicad_pcb
	(version 20260206)
	(generator "pcbnew")
	(generator_version "10.0")
	(general
		(thickness 1.6)
		(legacy_teardrops no)
	)
	(paper "A4")
	(title_block
		(title "04192023_DAF0TMB3IC0_F0TG_MB_C_brd_V02_OCP.brd")
		(comment 1 "Grand Teton / footprints 3729-3731 of 8354")
	)
	(layers
		(0 "F.Cu" signal "TOP")
		(4 "In1.Cu" signal "GND")
		(6 "In2.Cu" signal "IN1")
		(8 "In3.Cu" signal "GND1")
		(10 "In4.Cu" signal "IN2")
		(12 "In5.Cu" signal "GND2")
		(14 "In6.Cu" signal "IN3")
		(16 "In7.Cu" signal "GND3")
		(18 "In8.Cu" signal "VCC")
		(20 "In9.Cu" signal "VCC1")
		(22 "In10.Cu" signal "GND4")
		(24 "In11.Cu" signal "IN4")
		(26 "In12.Cu" signal "GND5")
		(28 "In13.Cu" signal "IN5")
		(30 "In14.Cu" signal "GND6")
		(32 "In15.Cu" signal "IN6")
		(34 "In16.Cu" signal "GND7")
		(2 "B.Cu" signal "BOTTOM")
		(9 "F.Adhes" user "F.Adhesive")
		(11 "B.Adhes" user "B.Adhesive")
		(13 "F.Paste" user "Package Geometry/Pastemask Top")
		(15 "B.Paste" user "Package Geometry/Pastemask Bottom")
		(5 "F.SilkS" user "Ref Des/Silkscreen Top")
		(7 "B.SilkS" user "Ref Des/Silkscreen Bottom")
		(1 "F.Mask" user "Board Geometry/Soldermask Top")
		(3 "B.Mask" user "Board Geometry/Soldermask Bottom")
		(17 "Dwgs.User" user "User.Drawings")
		(19 "Cmts.User" user "User.Comments")
		(21 "Eco1.User" user "User.Eco1")
		(23 "Eco2.User" user "User.Eco2")
		(25 "Edge.Cuts" user "Board Geometry/Outline")
		(27 "Margin" user)
		(31 "F.CrtYd" user "Package Geometry/Place Bound Top")
		(29 "B.CrtYd" user "Package Geometry/Place Bound Bottom")
		(35 "F.Fab" user "Ref Des/Assembly Top")
		(33 "B.Fab" user "Ref Des/Assembly Bottom")
	)
	(footprint ""
		(layer "F.Cu")
		(at 285.24454 -401.395692 180)
		(property "Reference" "C1786"
			(at 0 0 180)
			(layer "F.SilkS")
			(hide yes)
			(effects
				(font
					(size 1.27 1.27)
				)
			)
		)
		(property "Value" ""
			(at 0 0 180)
			(layer "F.Fab")
			(effects
				(font
					(size 1.27 1.27)
				)
			)
		)
		(duplicate_pad_numbers_are_jumpers no)
		(fp_line
			(start 1.2954 0.5842)
			(end -1.2954 0.5842)
			(stroke
				(width 0.1524)
				(type default)
			)
			(layer "F.SilkS")
		)
		(fp_line
			(start 1.2954 -0.5842)
			(end 1.2954 0.5842)
			(stroke
				(width 0.1524)
				(type default)
			)
			(layer "F.SilkS")
		)
		(fp_line
			(start -1.2954 0.5842)
			(end -1.2954 -0.5842)
			(stroke
				(width 0.1524)
				(type default)
			)
			(layer "F.SilkS")
		)
		(fp_line
			(start -1.2954 -0.5842)
			(end 1.2954 -0.5842)
			(stroke
				(width 0.1524)
				(type default)
			)
			(layer "F.SilkS")
		)
		(fp_line
			(start 1.1938 0.4064)
			(end 0.8636 0.4064)
			(stroke
				(width 0.1)
				(type default)
			)
			(layer "F.Fab")
		)
		(fp_line
			(start 1.1938 -0.4064)
			(end 1.1938 0.4064)
			(stroke
				(width 0.1)
				(type default)
			)
			(layer "F.Fab")
		)
		(fp_line
			(start 0.8636 0.4572)
			(end -0.8636 0.4572)
			(stroke
				(width 0.1)
				(type default)
			)
			(layer "F.Fab")
		)
		(fp_line
			(start 0.8636 0.4064)
			(end 0.8636 0.4572)
			(stroke
				(width 0.1)
				(type default)
			)
			(layer "F.Fab")
		)
		(fp_line
			(start 0.8636 -0.4064)
			(end 1.1938 -0.4064)
			(stroke
				(width 0.1)
				(type default)
			)
			(layer "F.Fab")
		)
		(fp_line
			(start 0.8636 -0.4572)
			(end 0.8636 -0.4064)
			(stroke
				(width 0.1)
				(type default)
			)
			(layer "F.Fab")
		)
		(fp_line
			(start -0.8636 0.4572)
			(end -0.8636 0.4064)
			(stroke
				(width 0.1)
				(type default)
			)
			(layer "F.Fab")
		)
		(fp_line
			(start -0.8636 0.4064)
			(end -1.1938 0.4064)
			(stroke
				(width 0.1)
				(type default)
			)
			(layer "F.Fab")
		)
		(fp_line
			(start -0.8636 -0.4064)
			(end -0.8636 -0.4572)
			(stroke
				(width 0.1)
				(type default)
			)
			(layer "F.Fab")
		)
		(fp_line
			(start -0.8636 -0.4572)
			(end 0.8636 -0.4572)
			(stroke
				(width 0.1)
				(type default)
			)
			(layer "F.Fab")
		)
		(fp_line
			(start -1.1938 0.4064)
			(end -1.1938 -0.4064)
			(stroke
				(width 0.1)
				(type default)
			)
			(layer "F.Fab")
		)
		(fp_line
			(start -1.1938 -0.4064)
			(end -0.8636 -0.4064)
			(stroke
				(width 0.1)
				(type default)
			)
			(layer "F.Fab")
		)
		(pad "1" smd rect
			(at -0.7366 0 90)
			(size 0.7112 0.8128)
			(layers "F.Cu" "F.Mask" "F.Paste")
			(net "P12V_HSC_TEMP_D+")
		)
		(pad "2" smd rect
			(at 0.7366 0 90)
			(size 0.7112 0.8128)
			(layers "F.Cu" "F.Mask" "F.Paste")
			(net "P12V_HSC_TEMP_D-")
		)
	)
	(footprint ""
		(layer "F.Cu")
		(at 148.944076 -23.284942 -90)
		(property "Reference" "R364"
			(at 0 0 270)
			(layer "F.SilkS")
			(hide yes)
			(effects
				(font
					(size 1.27 1.27)
				)
			)
		)
		(property "Value" ""
			(at 0 0 270)
			(layer "F.Fab")
			(effects
				(font
					(size 1.27 1.27)
				)
			)
		)
		(duplicate_pad_numbers_are_jumpers no)
		(fp_line
			(start -0.7874 0.4064)
			(end -0.7874 -0.4064)
			(stroke
				(width 0.1524)
				(type default)
			)
			(layer "F.SilkS")
		)
		(fp_line
			(start 0.7874 0.4064)
			(end -0.7874 0.4064)
			(stroke
				(width 0.1524)
				(type default)
			)
			(layer "F.SilkS")
		)
		(fp_line
			(start -0.7874 -0.4064)
			(end 0.7874 -0.4064)
			(stroke
				(width 0.1524)
				(type default)
			)
			(layer "F.SilkS")
		)
		(fp_line
			(start 0.7874 -0.4064)
			(end 0.7874 0.4064)
			(stroke
				(width 0.1524)
				(type default)
			)
			(layer "F.SilkS")
		)
		(fp_line
			(start -0.67945 0.3048)
			(end -0.67945 -0.305054)
			(stroke
				(width 0.1)
				(type default)
			)
			(layer "F.Fab")
		)
		(fp_line
			(start -0.12065 0.3048)
			(end -0.67945 0.3048)
			(stroke
				(width 0.1)
				(type default)
			)
			(layer "F.Fab")
		)
		(fp_line
			(start 0.120396 0.3048)
			(end 0.120396 0.2794)
			(stroke
				(width 0.1)
				(type default)
			)
			(layer "F.Fab")
		)
		(fp_line
			(start 0.67945 0.3048)
			(end 0.120396 0.3048)
			(stroke
				(width 0.1)
				(type default)
			)
			(layer "F.Fab")
		)
		(fp_line
			(start -0.12065 0.2794)
			(end -0.12065 0.3048)
			(stroke
				(width 0.1)
				(type default)
			)
			(layer "F.Fab")
		)
		(fp_line
			(start 0.120396 0.2794)
			(end -0.12065 0.2794)
			(stroke
				(width 0.1)
				(type default)
			)
			(layer "F.Fab")
		)
		(fp_line
			(start -0.12065 -0.2794)
			(end 0.12065 -0.2794)
			(stroke
				(width 0.1)
				(type default)
			)
			(layer "F.Fab")
		)
		(fp_line
			(start 0.12065 -0.2794)
			(end 0.12065 -0.3048)
			(stroke
				(width 0.1)
				(type default)
			)
			(layer "F.Fab")
		)
		(fp_line
			(start 0.12065 -0.3048)
			(end 0.67945 -0.3048)
			(stroke
				(width 0.1)
				(type default)
			)
			(layer "F.Fab")
		)
		(fp_line
			(start 0.67945 -0.3048)
			(end 0.67945 0.3048)
			(stroke
				(width 0.1)
				(type default)
			)
			(layer "F.Fab")
		)
		(fp_line
			(start -0.67945 -0.305054)
			(end -0.12065 -0.305054)
			(stroke
				(width 0.1)
				(type default)
			)
			(layer "F.Fab")
		)
		(fp_line
			(start -0.12065 -0.305054)
			(end -0.12065 -0.2794)
			(stroke
				(width 0.1)
				(type default)
			)
			(layer "F.Fab")
		)
		(pad "1" smd circle
			(at -0.40005 0 270)
			(size 0 0)
			(layers "F.Cu" "F.Mask" "F.Paste")
			(net "P3V_BAT_R")
		)
		(pad "2" smd circle
			(at 0.40005 0 270)
			(size 0 0)
			(layers "F.Cu" "F.Mask" "F.Paste")
			(net "SCM_VDD_RTC")
		)
	)
	(footprint ""
		(layer "F.Cu")
		(at 403.977348 -17.624298 90)
		(property "Reference" "C1558"
			(at 0 0 90)
			(layer "F.SilkS")
			(hide yes)
			(effects
				(font
					(size 1.27 1.27)
				)
			)
		)
		(property "Value" ""
			(at 0 0 90)
			(layer "F.Fab")
			(effects
				(font
					(size 1.27 1.27)
				)
			)
		)
		(duplicate_pad_numbers_are_jumpers no)
		(fp_line
			(start 0.299974 -0.150114)
			(end 0.299974 0.150114)
			(stroke
				(width 0.1)
				(type default)
			)
			(layer "F.Fab")
		)
		(fp_line
			(start -0.299974 -0.150114)
			(end 0.299974 -0.150114)
			(stroke
				(width 0.1)
				(type default)
			)
			(layer "F.Fab")
		)
		(fp_line
			(start 0.299974 0.150114)
			(end -0.299974 0.150114)
			(stroke
				(width 0.1)
				(type default)
			)
			(layer "F.Fab")
		)
		(fp_line
			(start -0.299974 0.150114)
			(end -0.299974 -0.150114)
			(stroke
				(width 0.1)
				(type default)
			)
			(layer "F.Fab")
		)
		(pad "1" smd rect
			(at -0.2667 0 90)
			(size 0.3048 0.381)
			(layers "F.Cu" "F.Mask" "F.Paste")
			(net "P5E_CPU0_G3_TX_C_DN<10>")
		)
		(pad "2" smd rect
			(at 0.2667 0 90)
			(size 0.3048 0.381)
			(layers "F.Cu" "F.Mask" "F.Paste")
			(net "P5E_CPU0_G3_TX_DN<10>")
		)
	)
)
